G04 ================== begin FILE IDENTIFICATION RECORD ==================*
G04 Layout Name:  17301-sa.brd*
G04 Film Name:    SE_REF_L6*
G04 File Format:  Gerber RS274X*
G04 File Origin:  Cadence Allegro 16.6-2015-S079*
G04 Origin Date:  Thu Jun 22 17:50:12 2017*
G04 *
G04 Layer:  BOARD GEOMETRY/PANEL_OUTLINE*
G04 Layer:  BOARD GEOMETRY/SE_REF_L6_TBL*
G04 Layer:  BOARD GEOMETRY/SE_REF_L6_BOTTOM*
G04 *
G04 Offset:    (0.00 0.00)*
G04 Mirror:    No*
G04 Mode:      Positive*
G04 Rotation:  0*
G04 FullContactRelief:  No*
G04 UndefLineWidth:     6.00*
G04 ================== end FILE IDENTIFICATION RECORD ====================*
%FSLAX35Y35*MOIN*%
%IR0*IPPOS*OFA0.00000B0.00000*MIA0B0*SFA1.00000B1.00000*%
%ADD10C,.02*%
%ADD11C,.006*%
%ADD12C,.0072*%
G75*
%LPD*%
G75*
G54D10*
G01X615261Y627846D02*
X1332761D01*
G01X615261Y697146D02*
Y627846D01*
G01Y662496D02*
X1332761D01*
G01X615261Y697146D02*
X1332761D01*
G01X790261D02*
Y627846D01*
G01X1017761Y697146D02*
Y627846D01*
G01X1122761Y697146D02*
Y627846D01*
G01X1332761Y697146D02*
Y627846D01*
G54D11*
G01X-19340Y-32800D02*
Y-50300D01*
G01X-24362Y-32800D02*
X-14318D01*
G01X-5552Y-50300D02*
Y-32800D01*
G01Y-41258D02*
X-4460Y-39800D01*
X-3368Y-38925D01*
X-1622Y-38634D01*
X-312Y-38925D01*
X1217Y-40092D01*
X1872Y-41842D01*
Y-50300D01*
G01X15660Y-38634D02*
Y-50300D01*
G01Y-33967D02*
X15223Y-33675D01*
Y-33092D01*
X15660Y-32800D01*
X16097Y-33092D01*
Y-33675D01*
X15660Y-33967D01*
G01X29885Y-48259D02*
X30977Y-49425D01*
X32505Y-50300D01*
X33815D01*
X35125Y-49717D01*
X35998Y-48842D01*
X36435Y-47676D01*
X36217Y-45925D01*
X35343Y-45050D01*
X31413Y-43300D01*
X30540Y-41258D01*
X30977Y-39800D01*
X31850Y-38925D01*
X33160Y-38634D01*
X34470Y-38925D01*
X35780Y-39800D01*
G01X65103Y-54675D02*
X66632Y-55842D01*
X68378Y-56133D01*
X69906Y-55842D01*
X71217Y-54384D01*
X72090Y-52342D01*
Y-38634D01*
G01Y-40967D02*
X71217Y-39800D01*
X69906Y-38925D01*
X68378Y-38634D01*
X66632Y-39217D01*
X65540Y-40383D01*
X64666Y-42425D01*
X64230Y-44467D01*
X64448Y-46217D01*
X65322Y-48259D01*
X66632Y-49717D01*
X68378Y-50300D01*
X69688Y-50008D01*
X71217Y-48842D01*
X72090Y-47676D01*
G01X82385Y-42425D02*
X89372D01*
X88717Y-40383D01*
X87625Y-39217D01*
X86097Y-38634D01*
X84568Y-38925D01*
X83258Y-39800D01*
X82385Y-41842D01*
X81948Y-43592D01*
Y-45342D01*
X82385Y-47092D01*
X83477Y-48842D01*
X84787Y-50008D01*
X86315Y-50300D01*
X87843Y-49717D01*
X89372Y-47967D01*
G01X100103Y-50300D02*
Y-38634D01*
G01Y-40967D02*
X101195Y-39800D01*
X102287Y-38925D01*
X103815Y-38634D01*
X104906Y-38925D01*
X106217Y-39800D01*
G01X116730Y-50300D02*
Y-32800D01*
G01Y-41550D02*
X117822Y-39800D01*
X119132Y-38925D01*
X120442Y-38634D01*
X122406Y-39217D01*
X123717Y-40383D01*
X124590Y-42425D01*
Y-44758D01*
X124153Y-47092D01*
X123280Y-48842D01*
X121752Y-50008D01*
X120442Y-50300D01*
X119132Y-50008D01*
X117822Y-49134D01*
X116730Y-47676D01*
G01X134885Y-42425D02*
X141872D01*
X141217Y-40383D01*
X140125Y-39217D01*
X138597Y-38634D01*
X137068Y-38925D01*
X135758Y-39800D01*
X134885Y-41842D01*
X134448Y-43592D01*
Y-45342D01*
X134885Y-47092D01*
X135977Y-48842D01*
X137287Y-50008D01*
X138815Y-50300D01*
X140343Y-49717D01*
X141872Y-47967D01*
G01X152603Y-50300D02*
Y-38634D01*
G01Y-40967D02*
X153695Y-39800D01*
X154787Y-38925D01*
X156315Y-38634D01*
X157406Y-38925D01*
X158717Y-39800D01*
G01X190660Y-38634D02*
Y-50300D01*
G01Y-33967D02*
X190223Y-33675D01*
Y-33092D01*
X190660Y-32800D01*
X191097Y-33092D01*
Y-33675D01*
X190660Y-33967D01*
G01X204885Y-48259D02*
X205977Y-49425D01*
X207505Y-50300D01*
X208815D01*
X210125Y-49717D01*
X210998Y-48842D01*
X211435Y-47676D01*
X211217Y-45925D01*
X210343Y-45050D01*
X206413Y-43300D01*
X205540Y-41258D01*
X205977Y-39800D01*
X206850Y-38925D01*
X208160Y-38634D01*
X209470Y-38925D01*
X210780Y-39800D01*
G01X239666Y-54675D02*
X241195Y-55842D01*
X242505Y-56133D01*
X244252Y-55550D01*
X245562Y-54092D01*
X246217Y-51466D01*
Y-38634D01*
G01Y-33967D02*
X245780Y-33675D01*
Y-33092D01*
X246217Y-32800D01*
X246653Y-33092D01*
Y-33675D01*
X246217Y-33967D01*
G01X256948Y-38634D02*
Y-46800D01*
X257822Y-48842D01*
X259132Y-50008D01*
X260660Y-50300D01*
X262188Y-50008D01*
X263498Y-48842D01*
X264372Y-46800D01*
G01Y-50300D02*
Y-38634D01*
G01X274885Y-48259D02*
X275977Y-49425D01*
X277505Y-50300D01*
X278815D01*
X280125Y-49717D01*
X280998Y-48842D01*
X281435Y-47676D01*
X281217Y-45925D01*
X280343Y-45050D01*
X276413Y-43300D01*
X275540Y-41258D01*
X275977Y-39800D01*
X276850Y-38925D01*
X278160Y-38634D01*
X279470Y-38925D01*
X280780Y-39800D01*
G01X295660Y-32800D02*
Y-50300D01*
G01X292603Y-38634D02*
X298717D01*
G01X329350Y-50300D02*
Y-35425D01*
X329787Y-33967D01*
X330660Y-33092D01*
X331970Y-32800D01*
X333280Y-33383D01*
X333935Y-34842D01*
G01X331315Y-39800D02*
X326948D01*
G01X348160Y-50300D02*
X346850Y-50008D01*
X345540Y-48842D01*
X344666Y-46800D01*
X344230Y-44467D01*
X344666Y-42133D01*
X345540Y-40092D01*
X346850Y-38925D01*
X348160Y-38634D01*
X349470Y-38925D01*
X350780Y-40092D01*
X351653Y-42133D01*
X351872Y-44467D01*
X351653Y-46800D01*
X350780Y-48842D01*
X349470Y-50008D01*
X348160Y-50300D01*
G01X362603D02*
Y-38634D01*
G01Y-40967D02*
X363695Y-39800D01*
X364787Y-38925D01*
X366315Y-38634D01*
X367406Y-38925D01*
X368717Y-39800D01*
G01X396075Y-55550D02*
X397385Y-56133D01*
X399132Y-55550D01*
X400223Y-54384D01*
X401097Y-52925D01*
X402406Y-48259D01*
X405245Y-38634D01*
G01X398258D02*
X402406Y-48259D01*
G01X418160Y-50300D02*
X416850Y-50008D01*
X415540Y-48842D01*
X414666Y-46800D01*
X414230Y-44467D01*
X414666Y-42133D01*
X415540Y-40092D01*
X416850Y-38925D01*
X418160Y-38634D01*
X419470Y-38925D01*
X420780Y-40092D01*
X421653Y-42133D01*
X421872Y-44467D01*
X421653Y-46800D01*
X420780Y-48842D01*
X419470Y-50008D01*
X418160Y-50300D01*
G01X431948Y-38634D02*
Y-46800D01*
X432822Y-48842D01*
X434132Y-50008D01*
X435660Y-50300D01*
X437188Y-50008D01*
X438498Y-48842D01*
X439372Y-46800D01*
G01Y-50300D02*
Y-38634D01*
G01X450103Y-50300D02*
Y-38634D01*
G01Y-40967D02*
X451195Y-39800D01*
X452287Y-38925D01*
X453815Y-38634D01*
X454906Y-38925D01*
X456217Y-39800D01*
G01X485103Y-50300D02*
Y-38634D01*
G01Y-40967D02*
X486195Y-39800D01*
X487287Y-38925D01*
X488815Y-38634D01*
X489906Y-38925D01*
X491217Y-39800D01*
G01X502385Y-42425D02*
X509372D01*
X508717Y-40383D01*
X507625Y-39217D01*
X506097Y-38634D01*
X504568Y-38925D01*
X503258Y-39800D01*
X502385Y-41842D01*
X501948Y-43592D01*
Y-45342D01*
X502385Y-47092D01*
X503477Y-48842D01*
X504787Y-50008D01*
X506315Y-50300D01*
X507843Y-49717D01*
X509372Y-47967D01*
G01X521850Y-50300D02*
Y-35425D01*
X522287Y-33967D01*
X523160Y-33092D01*
X524470Y-32800D01*
X525780Y-33383D01*
X526435Y-34842D01*
G01X523815Y-39800D02*
X519448D01*
G01X537385Y-42425D02*
X544372D01*
X543717Y-40383D01*
X542625Y-39217D01*
X541097Y-38634D01*
X539568Y-38925D01*
X538258Y-39800D01*
X537385Y-41842D01*
X536948Y-43592D01*
Y-45342D01*
X537385Y-47092D01*
X538477Y-48842D01*
X539787Y-50008D01*
X541315Y-50300D01*
X542843Y-49717D01*
X544372Y-47967D01*
G01X555103Y-50300D02*
Y-38634D01*
G01Y-40967D02*
X556195Y-39800D01*
X557287Y-38925D01*
X558815Y-38634D01*
X559906Y-38925D01*
X561217Y-39800D01*
G01X572385Y-42425D02*
X579372D01*
X578717Y-40383D01*
X577625Y-39217D01*
X576097Y-38634D01*
X574568Y-38925D01*
X573258Y-39800D01*
X572385Y-41842D01*
X571948Y-43592D01*
Y-45342D01*
X572385Y-47092D01*
X573477Y-48842D01*
X574787Y-50008D01*
X576315Y-50300D01*
X577843Y-49717D01*
X579372Y-47967D01*
G01X589448Y-50300D02*
Y-38634D01*
G01Y-41550D02*
X590322Y-40092D01*
X591632Y-38925D01*
X593378Y-38634D01*
X594906Y-38925D01*
X596217Y-40092D01*
X596872Y-42133D01*
Y-50300D01*
G01X614153Y-40092D02*
X612625Y-38925D01*
X611315Y-38634D01*
X609568Y-39217D01*
X608258Y-40383D01*
X607385Y-42425D01*
X607166Y-44467D01*
X607385Y-46509D01*
X608258Y-48259D01*
X609568Y-49717D01*
X611315Y-50300D01*
X612843Y-49717D01*
X614153Y-48550D01*
G01X624885Y-42425D02*
X631872D01*
X631217Y-40383D01*
X630125Y-39217D01*
X628597Y-38634D01*
X627068Y-38925D01*
X625758Y-39800D01*
X624885Y-41842D01*
X624448Y-43592D01*
Y-45342D01*
X624885Y-47092D01*
X625977Y-48842D01*
X627287Y-50008D01*
X628815Y-50300D01*
X630343Y-49717D01*
X631872Y-47967D01*
G01X663160Y-32800D02*
Y-50300D01*
G01X660103Y-38634D02*
X666217D01*
G01X680660Y-50300D02*
X679350Y-50008D01*
X678040Y-48842D01*
X677166Y-46800D01*
X676730Y-44467D01*
X677166Y-42133D01*
X678040Y-40092D01*
X679350Y-38925D01*
X680660Y-38634D01*
X681970Y-38925D01*
X683280Y-40092D01*
X684153Y-42133D01*
X684372Y-44467D01*
X684153Y-46800D01*
X683280Y-48842D01*
X681970Y-50008D01*
X680660Y-50300D01*
G01X714350D02*
Y-35425D01*
X714787Y-33967D01*
X715660Y-33092D01*
X716970Y-32800D01*
X718280Y-33383D01*
X718935Y-34842D01*
G01X716315Y-39800D02*
X711948D01*
G01X733160Y-38634D02*
Y-50300D01*
G01Y-33967D02*
X732723Y-33675D01*
Y-33092D01*
X733160Y-32800D01*
X733597Y-33092D01*
Y-33675D01*
X733160Y-33967D01*
G01X746948Y-50300D02*
Y-38634D01*
G01Y-41550D02*
X747822Y-40092D01*
X749132Y-38925D01*
X750878Y-38634D01*
X752406Y-38925D01*
X753717Y-40092D01*
X754372Y-42133D01*
Y-50300D01*
G01X772090Y-32800D02*
Y-50300D01*
G01Y-47676D02*
X771217Y-49134D01*
X769906Y-50008D01*
X768378Y-50300D01*
X766632Y-49717D01*
X765322Y-48259D01*
X764448Y-46509D01*
X764230Y-44467D01*
X764448Y-42425D01*
X765322Y-40675D01*
X766632Y-39217D01*
X768378Y-38634D01*
X769906Y-38925D01*
X770998Y-39509D01*
X772090Y-40675D01*
G01X803160Y-32800D02*
Y-50300D01*
G01X800103Y-38634D02*
X806217D01*
G01X816948Y-50300D02*
Y-32800D01*
G01Y-41258D02*
X818040Y-39800D01*
X819132Y-38925D01*
X820878Y-38634D01*
X822188Y-38925D01*
X823717Y-40092D01*
X824372Y-41842D01*
Y-50300D01*
G01X834885Y-42425D02*
X841872D01*
X841217Y-40383D01*
X840125Y-39217D01*
X838597Y-38634D01*
X837068Y-38925D01*
X835758Y-39800D01*
X834885Y-41842D01*
X834448Y-43592D01*
Y-45342D01*
X834885Y-47092D01*
X835977Y-48842D01*
X837287Y-50008D01*
X838815Y-50300D01*
X840343Y-49717D01*
X841872Y-47967D01*
G01X868575D02*
X870322Y-49425D01*
X872287Y-50300D01*
X874033D01*
X875780Y-49425D01*
X877090Y-47967D01*
X877745Y-45925D01*
X877308Y-43884D01*
X876217Y-42133D01*
X874252Y-40967D01*
X871632Y-40383D01*
X870103Y-39217D01*
X869448Y-37175D01*
X869885Y-35133D01*
X870977Y-33675D01*
X872505Y-32800D01*
X874033D01*
X875562Y-33383D01*
X876872Y-34842D01*
G01X895027Y-50300D02*
X886293D01*
Y-32800D01*
X895027D01*
G01X891533Y-41258D02*
X886293D01*
G01X925660Y-38634D02*
Y-50300D01*
G01Y-33967D02*
X925223Y-33675D01*
Y-33092D01*
X925660Y-32800D01*
X926097Y-33092D01*
Y-33675D01*
X925660Y-33967D01*
G01X936610Y-50300D02*
Y-38634D01*
G01Y-41842D02*
X937265Y-40383D01*
X938357Y-39217D01*
X939885Y-38634D01*
X941413Y-39217D01*
X942505Y-40383D01*
X943160Y-41842D01*
Y-50300D01*
G01Y-41842D02*
X943815Y-40383D01*
X944906Y-39217D01*
X946435Y-38634D01*
X947963Y-39217D01*
X949055Y-40383D01*
X949710Y-42133D01*
Y-50300D01*
G01X956730Y-56133D02*
Y-38634D01*
G01Y-41258D02*
X957822Y-39800D01*
X958913Y-38925D01*
X960660Y-38634D01*
X962188Y-38925D01*
X963717Y-40383D01*
X964372Y-42425D01*
X964590Y-44467D01*
X964372Y-46509D01*
X963717Y-48550D01*
X962406Y-49717D01*
X960660Y-50300D01*
X959132Y-50008D01*
X957603Y-49134D01*
X956730Y-47967D01*
G01X974885Y-42425D02*
X981872D01*
X981217Y-40383D01*
X980125Y-39217D01*
X978597Y-38634D01*
X977068Y-38925D01*
X975758Y-39800D01*
X974885Y-41842D01*
X974448Y-43592D01*
Y-45342D01*
X974885Y-47092D01*
X975977Y-48842D01*
X977287Y-50008D01*
X978815Y-50300D01*
X980343Y-49717D01*
X981872Y-47967D01*
G01X999590Y-32800D02*
Y-50300D01*
G01Y-47676D02*
X998717Y-49134D01*
X997406Y-50008D01*
X995878Y-50300D01*
X994132Y-49717D01*
X992822Y-48259D01*
X991948Y-46509D01*
X991730Y-44467D01*
X991948Y-42425D01*
X992822Y-40675D01*
X994132Y-39217D01*
X995878Y-38634D01*
X997406Y-38925D01*
X998498Y-39509D01*
X999590Y-40675D01*
G01X1017090Y-50300D02*
Y-38634D01*
G01Y-40675D02*
X1016217Y-39509D01*
X1014906Y-38925D01*
X1013378Y-38634D01*
X1011850Y-39217D01*
X1010540Y-40383D01*
X1009666Y-42133D01*
X1009230Y-44467D01*
X1009666Y-46800D01*
X1010540Y-48550D01*
X1011850Y-49717D01*
X1013378Y-50300D01*
X1014906Y-50008D01*
X1016217Y-49134D01*
X1017090Y-47967D01*
G01X1026948Y-50300D02*
Y-38634D01*
G01Y-41550D02*
X1027822Y-40092D01*
X1029132Y-38925D01*
X1030878Y-38634D01*
X1032406Y-38925D01*
X1033717Y-40092D01*
X1034372Y-42133D01*
Y-50300D01*
G01X1051653Y-40092D02*
X1050125Y-38925D01*
X1048815Y-38634D01*
X1047068Y-39217D01*
X1045758Y-40383D01*
X1044885Y-42425D01*
X1044666Y-44467D01*
X1044885Y-46509D01*
X1045758Y-48259D01*
X1047068Y-49717D01*
X1048815Y-50300D01*
X1050343Y-49717D01*
X1051653Y-48550D01*
G01X1062385Y-42425D02*
X1069372D01*
X1068717Y-40383D01*
X1067625Y-39217D01*
X1066097Y-38634D01*
X1064568Y-38925D01*
X1063258Y-39800D01*
X1062385Y-41842D01*
X1061948Y-43592D01*
Y-45342D01*
X1062385Y-47092D01*
X1063477Y-48842D01*
X1064787Y-50008D01*
X1066315Y-50300D01*
X1067843Y-49717D01*
X1069372Y-47967D01*
G01X1100660Y-32800D02*
Y-50300D01*
G01X1097603Y-38634D02*
X1103717D01*
G01X1115103Y-50300D02*
Y-38634D01*
G01Y-40967D02*
X1116195Y-39800D01*
X1117287Y-38925D01*
X1118815Y-38634D01*
X1119906Y-38925D01*
X1121217Y-39800D01*
G01X1139590Y-50300D02*
Y-38634D01*
G01Y-40675D02*
X1138717Y-39509D01*
X1137406Y-38925D01*
X1135878Y-38634D01*
X1134350Y-39217D01*
X1133040Y-40383D01*
X1132166Y-42133D01*
X1131730Y-44467D01*
X1132166Y-46800D01*
X1133040Y-48550D01*
X1134350Y-49717D01*
X1135878Y-50300D01*
X1137406Y-50008D01*
X1138717Y-49134D01*
X1139590Y-47967D01*
G01X1156653Y-40092D02*
X1155125Y-38925D01*
X1153815Y-38634D01*
X1152068Y-39217D01*
X1150758Y-40383D01*
X1149885Y-42425D01*
X1149666Y-44467D01*
X1149885Y-46509D01*
X1150758Y-48259D01*
X1152068Y-49717D01*
X1153815Y-50300D01*
X1155343Y-49717D01*
X1156653Y-48550D01*
G01X1167385Y-42425D02*
X1174372D01*
X1173717Y-40383D01*
X1172625Y-39217D01*
X1171097Y-38634D01*
X1169568Y-38925D01*
X1168258Y-39800D01*
X1167385Y-41842D01*
X1166948Y-43592D01*
Y-45342D01*
X1167385Y-47092D01*
X1168477Y-48842D01*
X1169787Y-50008D01*
X1171315Y-50300D01*
X1172843Y-49717D01*
X1174372Y-47967D01*
G01X1184885Y-48259D02*
X1185977Y-49425D01*
X1187505Y-50300D01*
X1188815D01*
X1190125Y-49717D01*
X1190998Y-48842D01*
X1191435Y-47676D01*
X1191217Y-45925D01*
X1190343Y-45050D01*
X1186413Y-43300D01*
X1185540Y-41258D01*
X1185977Y-39800D01*
X1186850Y-38925D01*
X1188160Y-38634D01*
X1189470Y-38925D01*
X1190780Y-39800D01*
G01X1223160Y-38634D02*
Y-50300D01*
G01Y-33967D02*
X1222723Y-33675D01*
Y-33092D01*
X1223160Y-32800D01*
X1223597Y-33092D01*
Y-33675D01*
X1223160Y-33967D01*
G01X1236948Y-50300D02*
Y-38634D01*
G01Y-41550D02*
X1237822Y-40092D01*
X1239132Y-38925D01*
X1240878Y-38634D01*
X1242406Y-38925D01*
X1243717Y-40092D01*
X1244372Y-42133D01*
Y-50300D01*
G01X1275660D02*
Y-32800D01*
G01X1297090Y-50300D02*
Y-38634D01*
G01Y-40675D02*
X1296217Y-39509D01*
X1294906Y-38925D01*
X1293378Y-38634D01*
X1291850Y-39217D01*
X1290540Y-40383D01*
X1289666Y-42133D01*
X1289230Y-44467D01*
X1289666Y-46800D01*
X1290540Y-48550D01*
X1291850Y-49717D01*
X1293378Y-50300D01*
X1294906Y-50008D01*
X1296217Y-49134D01*
X1297090Y-47967D01*
G01X1306075Y-55550D02*
X1307385Y-56133D01*
X1309132Y-55550D01*
X1310223Y-54384D01*
X1311097Y-52925D01*
X1312406Y-48259D01*
X1315245Y-38634D01*
G01X1308258D02*
X1312406Y-48259D01*
G01X1324885Y-42425D02*
X1331872D01*
X1331217Y-40383D01*
X1330125Y-39217D01*
X1328597Y-38634D01*
X1327068Y-38925D01*
X1325758Y-39800D01*
X1324885Y-41842D01*
X1324448Y-43592D01*
Y-45342D01*
X1324885Y-47092D01*
X1325977Y-48842D01*
X1327287Y-50008D01*
X1328815Y-50300D01*
X1330343Y-49717D01*
X1331872Y-47967D01*
G01X1342603Y-50300D02*
Y-38634D01*
G01Y-40967D02*
X1343695Y-39800D01*
X1344787Y-38925D01*
X1346315Y-38634D01*
X1347406Y-38925D01*
X1348717Y-39800D01*
G01X1376293Y-32800D02*
Y-50300D01*
X1385027D01*
G01X1394012Y-43009D02*
X1395540Y-40967D01*
X1396850Y-39800D01*
X1398597Y-39217D01*
X1400125Y-39800D01*
X1401217Y-40967D01*
X1402090Y-42717D01*
X1402308Y-44758D01*
X1402090Y-46509D01*
X1401217Y-48259D01*
X1399906Y-49717D01*
X1398378Y-50300D01*
X1396632Y-49717D01*
X1395103Y-47967D01*
X1394230Y-45342D01*
X1394012Y-42425D01*
X1394448Y-38634D01*
X1395103Y-36591D01*
X1396195Y-34550D01*
X1397723Y-33092D01*
X1399252Y-32800D01*
X1400780Y-33383D01*
X1401872Y-34842D01*
G01X1415660Y-50883D02*
X1415223Y-50592D01*
Y-50008D01*
X1415660Y-49717D01*
X1416097Y-50008D01*
Y-50592D01*
X1415660Y-50883D01*
G01X617226Y709229D02*
X618973Y707771D01*
X620938Y706896D01*
X622684D01*
X624431Y707771D01*
X625741Y709229D01*
X626396Y711271D01*
X625959Y713312D01*
X624868Y715063D01*
X622903Y716229D01*
X620283Y716813D01*
X618754Y717979D01*
X618099Y720021D01*
X618536Y722063D01*
X619628Y723521D01*
X621156Y724396D01*
X622684D01*
X624213Y723813D01*
X625523Y722354D01*
G01X643678Y706896D02*
X634944D01*
Y724396D01*
X643678D01*
G01X640184Y715938D02*
X634944D01*
G01X671691Y724396D02*
X676931D01*
G01X674311D02*
Y706896D01*
G01X671691D02*
X676931D01*
G01X686134D02*
Y724396D01*
X691811Y709813D01*
X697488Y724396D01*
Y706896D01*
G01X704944D02*
Y724396D01*
X710184D01*
X711931Y723521D01*
X713241Y721479D01*
X713678Y719146D01*
X713241Y716813D01*
X712149Y715063D01*
X710184Y714187D01*
X704944D01*
G01X731178Y706896D02*
X722444D01*
Y724396D01*
X731178D01*
G01X727684Y715938D02*
X722444D01*
G01X739508Y706896D02*
Y724396D01*
X743874D01*
X745621Y723521D01*
X746931Y722354D01*
X748023Y720605D01*
X748896Y718562D01*
X749114Y715646D01*
X748896Y712729D01*
X748023Y710687D01*
X746931Y708937D01*
X745621Y707771D01*
X743874Y706896D01*
X739508D01*
G01X756352D02*
X761811Y724396D01*
X767270Y706896D01*
G01X765304Y713021D02*
X758317D01*
G01X774289Y706896D02*
Y724396D01*
X784333Y706896D01*
Y724396D01*
G01X801614Y722937D02*
X800304Y723813D01*
X798776Y724396D01*
X797029D01*
X795064Y723521D01*
X793536Y722063D01*
X792444Y720312D01*
X791571Y717396D01*
X791352Y714771D01*
X791789Y712146D01*
X792444Y710396D01*
X793754Y708646D01*
X795283Y707479D01*
X796811Y706896D01*
X798339D01*
X799868Y707479D01*
X801178Y708354D01*
X802270Y709520D01*
G01X818678Y706896D02*
X809944D01*
Y724396D01*
X818678D01*
G01X815184Y715938D02*
X809944D01*
G01X849311Y724396D02*
Y706896D01*
G01X844289Y724396D02*
X854333D01*
G01X861352Y706896D02*
X866811Y724396D01*
X872270Y706896D01*
G01X870304Y713021D02*
X863317D01*
G01X886057Y716229D02*
X886931Y717104D01*
X887586Y718562D01*
X888023Y720605D01*
X887586Y722354D01*
X886713Y723521D01*
X885184Y724396D01*
X879289D01*
Y706896D01*
X886494D01*
X888023Y708062D01*
X888896Y709813D01*
X889333Y711854D01*
X888896Y713896D01*
X887586Y715646D01*
X886057Y716229D01*
X879289D01*
G01X897444Y724396D02*
Y706896D01*
X906178D01*
G01X923678D02*
X914944D01*
Y724396D01*
X923678D01*
G01X920184Y715938D02*
X914944D01*
G01X936811Y706313D02*
X936374Y706604D01*
Y707188D01*
X936811Y707479D01*
X937248Y707188D01*
Y706604D01*
X936811Y706313D01*
G01Y714187D02*
X936374Y714479D01*
Y715063D01*
X936811Y715354D01*
X937248Y715063D01*
Y714479D01*
X936811Y714187D01*
G01X967444Y724396D02*
Y706896D01*
X976178D01*
G01X985163Y714187D02*
X986691Y716229D01*
X988001Y717396D01*
X989748Y717979D01*
X991276Y717396D01*
X992368Y716229D01*
X993241Y714479D01*
X993459Y712438D01*
X993241Y710687D01*
X992368Y708937D01*
X991057Y707479D01*
X989529Y706896D01*
X987783Y707479D01*
X986254Y709229D01*
X985381Y711854D01*
X985163Y714771D01*
X985599Y718562D01*
X986254Y720605D01*
X987346Y722646D01*
X988874Y724104D01*
X990403Y724396D01*
X991931Y723813D01*
X993023Y722354D01*
G01X638891Y689746D02*
X644131D01*
G01X641511D02*
Y672246D01*
G01X638891D02*
X644131D01*
G01X653334D02*
Y689746D01*
X659011Y675163D01*
X664688Y689746D01*
Y672246D01*
G01X672144D02*
Y689746D01*
X677384D01*
X679131Y688871D01*
X680441Y686829D01*
X680878Y684496D01*
X680441Y682163D01*
X679349Y680413D01*
X677384Y679537D01*
X672144D01*
G01X692919Y666413D02*
X690736Y669329D01*
X689644Y672246D01*
Y683912D01*
X690736Y686829D01*
X692919Y689746D01*
G01X711511Y672246D02*
X709764Y672538D01*
X708236Y673704D01*
X706926Y675454D01*
X706052Y677496D01*
X705616Y679829D01*
Y682163D01*
X706052Y684496D01*
X706926Y686538D01*
X708236Y688287D01*
X709764Y689454D01*
X711511Y689746D01*
X713257Y689454D01*
X714786Y688287D01*
X716096Y686538D01*
X716970Y684496D01*
X717406Y682163D01*
Y679829D01*
X716970Y677496D01*
X716096Y675454D01*
X714786Y673704D01*
X713257Y672538D01*
X711511Y672246D01*
G01X725299D02*
Y689746D01*
G01Y681288D02*
X726391Y682746D01*
X727483Y683621D01*
X729229Y683912D01*
X730539Y683621D01*
X732068Y682454D01*
X732723Y680704D01*
Y672246D01*
G01X739961D02*
Y683912D01*
G01Y680704D02*
X740616Y682163D01*
X741708Y683329D01*
X743236Y683912D01*
X744764Y683329D01*
X745856Y682163D01*
X746511Y680704D01*
Y672246D01*
G01Y680704D02*
X747166Y682163D01*
X748257Y683329D01*
X749786Y683912D01*
X751314Y683329D01*
X752406Y682163D01*
X753061Y680413D01*
Y672246D01*
G01X765103Y666413D02*
X767286Y669329D01*
X768378Y672246D01*
Y683912D01*
X767286Y686829D01*
X765103Y689746D01*
G01X671708Y640220D02*
X673017Y638762D01*
X674546Y637888D01*
X676511Y637596D01*
X678476Y638179D01*
X680004Y639346D01*
X681096Y641387D01*
X681314Y643721D01*
X680878Y646054D01*
X679786Y647513D01*
X678257Y648679D01*
X676729Y648971D01*
X675201Y648679D01*
X673236Y647513D01*
X673891Y655096D01*
X679786D01*
G01X694011D02*
X692264Y654513D01*
X690954Y653054D01*
X690081Y651305D01*
X689426Y648971D01*
X689208Y646346D01*
X689426Y643721D01*
X690081Y641387D01*
X690954Y639637D01*
X692264Y638179D01*
X694011Y637596D01*
X695757Y638179D01*
X697068Y639637D01*
X697941Y641387D01*
X698596Y643721D01*
X698814Y646346D01*
X698596Y648971D01*
X697941Y651305D01*
X697068Y653054D01*
X695757Y654513D01*
X694011Y655096D01*
G01X711511Y637013D02*
X711074Y637304D01*
Y637888D01*
X711511Y638179D01*
X711948Y637888D01*
Y637304D01*
X711511Y637013D01*
G01X729011Y655096D02*
X727264Y654513D01*
X725954Y653054D01*
X725081Y651305D01*
X724426Y648971D01*
X724208Y646346D01*
X724426Y643721D01*
X725081Y641387D01*
X725954Y639637D01*
X727264Y638179D01*
X729011Y637596D01*
X730757Y638179D01*
X732068Y639637D01*
X732941Y641387D01*
X733596Y643721D01*
X733814Y646346D01*
X733596Y648971D01*
X732941Y651305D01*
X732068Y653054D01*
X730757Y654513D01*
X729011Y655096D01*
G01X809961Y689746D02*
X813017Y672246D01*
X816511Y689746D01*
X820004Y672246D01*
X823061Y689746D01*
G01X831391D02*
X836631D01*
G01X834011D02*
Y672246D01*
G01X831391D02*
X836631D01*
G01X846708D02*
Y689746D01*
X851074D01*
X852821Y688871D01*
X854131Y687704D01*
X855223Y685955D01*
X856096Y683912D01*
X856314Y680996D01*
X856096Y678079D01*
X855223Y676037D01*
X854131Y674287D01*
X852821Y673121D01*
X851074Y672246D01*
X846708D01*
G01X869011Y689746D02*
Y672246D01*
G01X863989Y689746D02*
X874033D01*
G01X881926Y672246D02*
Y689746D01*
G01X891096D02*
Y672246D01*
G01Y680996D02*
X881926D01*
G01X902919Y666413D02*
X900736Y669329D01*
X899644Y672246D01*
Y683912D01*
X900736Y686829D01*
X902919Y689746D01*
G01X914961Y672246D02*
Y683912D01*
G01Y680704D02*
X915616Y682163D01*
X916708Y683329D01*
X918236Y683912D01*
X919764Y683329D01*
X920856Y682163D01*
X921511Y680704D01*
Y672246D01*
G01Y680704D02*
X922166Y682163D01*
X923257Y683329D01*
X924786Y683912D01*
X926314Y683329D01*
X927406Y682163D01*
X928061Y680413D01*
Y672246D01*
G01X939011Y683912D02*
Y672246D01*
G01Y688579D02*
X938574Y688871D01*
Y689454D01*
X939011Y689746D01*
X939448Y689454D01*
Y688871D01*
X939011Y688579D01*
G01X956511Y672246D02*
Y689746D01*
G01X970736Y674287D02*
X971828Y673121D01*
X973356Y672246D01*
X974666D01*
X975976Y672829D01*
X976849Y673704D01*
X977286Y674870D01*
X977068Y676621D01*
X976194Y677496D01*
X972264Y679246D01*
X971391Y681288D01*
X971828Y682746D01*
X972701Y683621D01*
X974011Y683912D01*
X975321Y683621D01*
X976631Y682746D01*
G01X992603Y666413D02*
X994786Y669329D01*
X995878Y672246D01*
Y683912D01*
X994786Y686829D01*
X992603Y689746D01*
G01X886074Y637596D02*
X886511Y641387D01*
X887166Y644596D01*
X888039Y647513D01*
X889131Y650721D01*
X890878Y655096D01*
X882144D01*
G01X904011Y637013D02*
X903574Y637304D01*
Y637888D01*
X904011Y638179D01*
X904448Y637888D01*
Y637304D01*
X904011Y637013D01*
G01X917363Y652179D02*
X918673Y653929D01*
X920201Y654804D01*
X921948Y655096D01*
X924131Y654513D01*
X925659Y653054D01*
X926096Y651305D01*
X925878Y649554D01*
X925004Y648096D01*
X920638Y645179D01*
X918673Y643138D01*
X917363Y640220D01*
X916926Y637596D01*
X926096D01*
G01X1044011Y689746D02*
Y672246D01*
G01X1038989Y689746D02*
X1049033D01*
G01X1061511Y672246D02*
Y680121D01*
X1057144Y689746D01*
G01X1065878D02*
X1061511Y680121D01*
G01X1074644Y672246D02*
Y689746D01*
X1079884D01*
X1081631Y688871D01*
X1082941Y686829D01*
X1083378Y684496D01*
X1082941Y682163D01*
X1081849Y680413D01*
X1079884Y679537D01*
X1074644D01*
G01X1100878Y672246D02*
X1092144D01*
Y689746D01*
X1100878D01*
G01X1097384Y681288D02*
X1092144D01*
G01X1056926Y639929D02*
X1058673Y638471D01*
X1060638Y637596D01*
X1062384D01*
X1064131Y638471D01*
X1065441Y639929D01*
X1066096Y641971D01*
X1065659Y644012D01*
X1064568Y645763D01*
X1062603Y646929D01*
X1059983Y647513D01*
X1058454Y648679D01*
X1057799Y650721D01*
X1058236Y652763D01*
X1059328Y654221D01*
X1060856Y655096D01*
X1062384D01*
X1063913Y654513D01*
X1065223Y653054D01*
G01X1083378Y637596D02*
X1074644D01*
Y655096D01*
X1083378D01*
G01X1079884Y646638D02*
X1074644D01*
G01X1144644Y672246D02*
Y689746D01*
X1150103D01*
X1151849Y688871D01*
X1152941Y687704D01*
X1153378Y685371D01*
X1152941Y683037D01*
X1151631Y681579D01*
X1150103Y680704D01*
X1144644D01*
G01X1150103D02*
X1153378Y672246D01*
G01X1163236Y680121D02*
X1170223D01*
X1169568Y682163D01*
X1168476Y683329D01*
X1166948Y683912D01*
X1165419Y683621D01*
X1164109Y682746D01*
X1163236Y680704D01*
X1162799Y678954D01*
Y677204D01*
X1163236Y675454D01*
X1164328Y673704D01*
X1165638Y672538D01*
X1167166Y672246D01*
X1168694Y672829D01*
X1170223Y674579D01*
G01X1182701Y672246D02*
Y687121D01*
X1183138Y688579D01*
X1184011Y689454D01*
X1185321Y689746D01*
X1186631Y689163D01*
X1187286Y687704D01*
G01X1184666Y682746D02*
X1180299D01*
G01X1201511Y671663D02*
X1201074Y671954D01*
Y672538D01*
X1201511Y672829D01*
X1201948Y672538D01*
Y671954D01*
X1201511Y671663D01*
G01X1232144Y672246D02*
Y689746D01*
X1237384D01*
X1239131Y688871D01*
X1240441Y686829D01*
X1240878Y684496D01*
X1240441Y682163D01*
X1239349Y680413D01*
X1237384Y679537D01*
X1232144D01*
G01X1254011Y672246D02*
Y689746D01*
G01X1275441Y672246D02*
Y683912D01*
G01Y681871D02*
X1274568Y683037D01*
X1273257Y683621D01*
X1271729Y683912D01*
X1270201Y683329D01*
X1268891Y682163D01*
X1268017Y680413D01*
X1267581Y678079D01*
X1268017Y675746D01*
X1268891Y673996D01*
X1270201Y672829D01*
X1271729Y672246D01*
X1273257Y672538D01*
X1274568Y673412D01*
X1275441Y674579D01*
G01X1285299Y672246D02*
Y683912D01*
G01Y680996D02*
X1286173Y682454D01*
X1287483Y683621D01*
X1289229Y683912D01*
X1290757Y683621D01*
X1292068Y682454D01*
X1292723Y680413D01*
Y672246D01*
G01X1303236Y680121D02*
X1310223D01*
X1309568Y682163D01*
X1308476Y683329D01*
X1306948Y683912D01*
X1305419Y683621D01*
X1304109Y682746D01*
X1303236Y680704D01*
X1302799Y678954D01*
Y677204D01*
X1303236Y675454D01*
X1304328Y673704D01*
X1305638Y672538D01*
X1307166Y672246D01*
X1308694Y672829D01*
X1310223Y674579D01*
G01X1214644Y655096D02*
Y637596D01*
X1223378D01*
G01X1231708Y640220D02*
X1233017Y638762D01*
X1234546Y637888D01*
X1236511Y637596D01*
X1238476Y638179D01*
X1240004Y639346D01*
X1241096Y641387D01*
X1241314Y643721D01*
X1240878Y646054D01*
X1239786Y647513D01*
X1238257Y648679D01*
X1236729Y648971D01*
X1235201Y648679D01*
X1233236Y647513D01*
X1233891Y655096D01*
X1239786D01*
G01X1424311Y649262D02*
Y637596D01*
G01Y653929D02*
X1423874Y654221D01*
Y654804D01*
X1424311Y655096D01*
X1424748Y654804D01*
Y654221D01*
X1424311Y653929D01*
G01X1438536Y639637D02*
X1439628Y638471D01*
X1441156Y637596D01*
X1442466D01*
X1443776Y638179D01*
X1444649Y639054D01*
X1445086Y640220D01*
X1444868Y641971D01*
X1443994Y642846D01*
X1440064Y644596D01*
X1439191Y646638D01*
X1439628Y648096D01*
X1440501Y648971D01*
X1441811Y649262D01*
X1443121Y648971D01*
X1444431Y648096D01*
G01X1471789Y637596D02*
Y655096D01*
X1481833Y637596D01*
Y655096D01*
G01X1494311Y637596D02*
X1492564Y637888D01*
X1491036Y639054D01*
X1489726Y640804D01*
X1488852Y642846D01*
X1488416Y645179D01*
Y647513D01*
X1488852Y649846D01*
X1489726Y651888D01*
X1491036Y653637D01*
X1492564Y654804D01*
X1494311Y655096D01*
X1496057Y654804D01*
X1497586Y653637D01*
X1498896Y651888D01*
X1499770Y649846D01*
X1500206Y647513D01*
Y645179D01*
X1499770Y642846D01*
X1498896Y640804D01*
X1497586Y639054D01*
X1496057Y637888D01*
X1494311Y637596D01*
G01X1511811Y655096D02*
Y637596D01*
G01X1506789Y655096D02*
X1516833D01*
G01X1543099Y649262D02*
Y641096D01*
X1543973Y639054D01*
X1545283Y637888D01*
X1546811Y637596D01*
X1548339Y637888D01*
X1549649Y639054D01*
X1550523Y641096D01*
G01Y637596D02*
Y649262D01*
G01X1561036Y639637D02*
X1562128Y638471D01*
X1563656Y637596D01*
X1564966D01*
X1566276Y638179D01*
X1567149Y639054D01*
X1567586Y640220D01*
X1567368Y641971D01*
X1566494Y642846D01*
X1562564Y644596D01*
X1561691Y646638D01*
X1562128Y648096D01*
X1563001Y648971D01*
X1564311Y649262D01*
X1565621Y648971D01*
X1566931Y648096D01*
G01X1578536Y645471D02*
X1585523D01*
X1584868Y647513D01*
X1583776Y648679D01*
X1582248Y649262D01*
X1580719Y648971D01*
X1579409Y648096D01*
X1578536Y646054D01*
X1578099Y644304D01*
Y642554D01*
X1578536Y640804D01*
X1579628Y639054D01*
X1580938Y637888D01*
X1582466Y637596D01*
X1583994Y638179D01*
X1585523Y639929D01*
G01X1603241Y655096D02*
Y637596D01*
G01Y640220D02*
X1602368Y638762D01*
X1601057Y637888D01*
X1599529Y637596D01*
X1597783Y638179D01*
X1596473Y639637D01*
X1595599Y641387D01*
X1595381Y643429D01*
X1595599Y645471D01*
X1596473Y647221D01*
X1597783Y648679D01*
X1599529Y649262D01*
X1601057Y648971D01*
X1602149Y648387D01*
X1603241Y647221D01*
G01X1349508Y671663D02*
X1359114Y684496D01*
G01X1354311Y686829D02*
Y669329D01*
G01X1359114Y671663D02*
X1349508Y684496D01*
G01X1347761Y678079D02*
X1360861D01*
G01X1386473D02*
X1392149D01*
G01X1419508Y672246D02*
Y689746D01*
X1423874D01*
X1425621Y688871D01*
X1426931Y687704D01*
X1428023Y685955D01*
X1428896Y683912D01*
X1429114Y680996D01*
X1428896Y678079D01*
X1428023Y676037D01*
X1426931Y674287D01*
X1425621Y673121D01*
X1423874Y672246D01*
X1419508D01*
G01X1438536Y680121D02*
X1445523D01*
X1444868Y682163D01*
X1443776Y683329D01*
X1442248Y683912D01*
X1440719Y683621D01*
X1439409Y682746D01*
X1438536Y680704D01*
X1438099Y678954D01*
Y677204D01*
X1438536Y675454D01*
X1439628Y673704D01*
X1440938Y672538D01*
X1442466Y672246D01*
X1443994Y672829D01*
X1445523Y674579D01*
G01X1455599Y672246D02*
Y683912D01*
G01Y680996D02*
X1456473Y682454D01*
X1457783Y683621D01*
X1459529Y683912D01*
X1461057Y683621D01*
X1462368Y682454D01*
X1463023Y680413D01*
Y672246D01*
G01X1476811D02*
X1475501Y672538D01*
X1474191Y673704D01*
X1473317Y675746D01*
X1472881Y678079D01*
X1473317Y680413D01*
X1474191Y682454D01*
X1475501Y683621D01*
X1476811Y683912D01*
X1478121Y683621D01*
X1479431Y682454D01*
X1480304Y680413D01*
X1480523Y678079D01*
X1480304Y675746D01*
X1479431Y673704D01*
X1478121Y672538D01*
X1476811Y672246D01*
G01X1494311Y689746D02*
Y672246D01*
G01X1491254Y683912D02*
X1497368D01*
G01X1508536Y680121D02*
X1515523D01*
X1514868Y682163D01*
X1513776Y683329D01*
X1512248Y683912D01*
X1510719Y683621D01*
X1509409Y682746D01*
X1508536Y680704D01*
X1508099Y678954D01*
Y677204D01*
X1508536Y675454D01*
X1509628Y673704D01*
X1510938Y672538D01*
X1512466Y672246D01*
X1513994Y672829D01*
X1515523Y674579D01*
G01X1526036Y674287D02*
X1527128Y673121D01*
X1528656Y672246D01*
X1529966D01*
X1531276Y672829D01*
X1532149Y673704D01*
X1532586Y674870D01*
X1532368Y676621D01*
X1531494Y677496D01*
X1527564Y679246D01*
X1526691Y681288D01*
X1527128Y682746D01*
X1528001Y683621D01*
X1529311Y683912D01*
X1530621Y683621D01*
X1531931Y682746D01*
G01X1564311Y689746D02*
Y672246D01*
G01X1561254Y683912D02*
X1567368D01*
G01X1578099Y672246D02*
Y689746D01*
G01Y681288D02*
X1579191Y682746D01*
X1580283Y683621D01*
X1582029Y683912D01*
X1583339Y683621D01*
X1584868Y682454D01*
X1585523Y680704D01*
Y672246D01*
G01X1603241D02*
Y683912D01*
G01Y681871D02*
X1602368Y683037D01*
X1601057Y683621D01*
X1599529Y683912D01*
X1598001Y683329D01*
X1596691Y682163D01*
X1595817Y680413D01*
X1595381Y678079D01*
X1595817Y675746D01*
X1596691Y673996D01*
X1598001Y672829D01*
X1599529Y672246D01*
X1601057Y672538D01*
X1602368Y673412D01*
X1603241Y674579D01*
G01X1616811Y689746D02*
Y672246D01*
G01X1613754Y683912D02*
X1619868D01*
G01X1651811Y689746D02*
Y672246D01*
G01X1648754Y683912D02*
X1654868D01*
G01X1665599Y672246D02*
Y689746D01*
G01Y681288D02*
X1666691Y682746D01*
X1667783Y683621D01*
X1669529Y683912D01*
X1670839Y683621D01*
X1672368Y682454D01*
X1673023Y680704D01*
Y672246D01*
G01X1686811Y683912D02*
Y672246D01*
G01Y688579D02*
X1686374Y688871D01*
Y689454D01*
X1686811Y689746D01*
X1687248Y689454D01*
Y688871D01*
X1686811Y688579D01*
G01X1701036Y674287D02*
X1702128Y673121D01*
X1703656Y672246D01*
X1704966D01*
X1706276Y672829D01*
X1707149Y673704D01*
X1707586Y674870D01*
X1707368Y676621D01*
X1706494Y677496D01*
X1702564Y679246D01*
X1701691Y681288D01*
X1702128Y682746D01*
X1703001Y683621D01*
X1704311Y683912D01*
X1705621Y683621D01*
X1706931Y682746D01*
G01X1736691Y689746D02*
X1741931D01*
G01X1739311D02*
Y672246D01*
G01X1736691D02*
X1741931D01*
G01X1750261D02*
Y683912D01*
G01Y680704D02*
X1750916Y682163D01*
X1752008Y683329D01*
X1753536Y683912D01*
X1755064Y683329D01*
X1756156Y682163D01*
X1756811Y680704D01*
Y672246D01*
G01Y680704D02*
X1757466Y682163D01*
X1758557Y683329D01*
X1760086Y683912D01*
X1761614Y683329D01*
X1762706Y682163D01*
X1763361Y680413D01*
Y672246D01*
G01X1770381Y666413D02*
Y683912D01*
G01Y681288D02*
X1771473Y682746D01*
X1772564Y683621D01*
X1774311Y683912D01*
X1775839Y683621D01*
X1777368Y682163D01*
X1778023Y680121D01*
X1778241Y678079D01*
X1778023Y676037D01*
X1777368Y673996D01*
X1776057Y672829D01*
X1774311Y672246D01*
X1772783Y672538D01*
X1771254Y673412D01*
X1770381Y674579D01*
G01X1788536Y680121D02*
X1795523D01*
X1794868Y682163D01*
X1793776Y683329D01*
X1792248Y683912D01*
X1790719Y683621D01*
X1789409Y682746D01*
X1788536Y680704D01*
X1788099Y678954D01*
Y677204D01*
X1788536Y675454D01*
X1789628Y673704D01*
X1790938Y672538D01*
X1792466Y672246D01*
X1793994Y672829D01*
X1795523Y674579D01*
G01X1813241Y689746D02*
Y672246D01*
G01Y674870D02*
X1812368Y673412D01*
X1811057Y672538D01*
X1809529Y672246D01*
X1807783Y672829D01*
X1806473Y674287D01*
X1805599Y676037D01*
X1805381Y678079D01*
X1805599Y680121D01*
X1806473Y681871D01*
X1807783Y683329D01*
X1809529Y683912D01*
X1811057Y683621D01*
X1812149Y683037D01*
X1813241Y681871D01*
G01X1830741Y672246D02*
Y683912D01*
G01Y681871D02*
X1829868Y683037D01*
X1828557Y683621D01*
X1827029Y683912D01*
X1825501Y683329D01*
X1824191Y682163D01*
X1823317Y680413D01*
X1822881Y678079D01*
X1823317Y675746D01*
X1824191Y673996D01*
X1825501Y672829D01*
X1827029Y672246D01*
X1828557Y672538D01*
X1829868Y673412D01*
X1830741Y674579D01*
G01X1840599Y672246D02*
Y683912D01*
G01Y680996D02*
X1841473Y682454D01*
X1842783Y683621D01*
X1844529Y683912D01*
X1846057Y683621D01*
X1847368Y682454D01*
X1848023Y680413D01*
Y672246D01*
G01X1865304Y682454D02*
X1863776Y683621D01*
X1862466Y683912D01*
X1860719Y683329D01*
X1859409Y682163D01*
X1858536Y680121D01*
X1858317Y678079D01*
X1858536Y676037D01*
X1859409Y674287D01*
X1860719Y672829D01*
X1862466Y672246D01*
X1863994Y672829D01*
X1865304Y673996D01*
G01X1876036Y680121D02*
X1883023D01*
X1882368Y682163D01*
X1881276Y683329D01*
X1879748Y683912D01*
X1878219Y683621D01*
X1876909Y682746D01*
X1876036Y680704D01*
X1875599Y678954D01*
Y677204D01*
X1876036Y675454D01*
X1877128Y673704D01*
X1878438Y672538D01*
X1879966Y672246D01*
X1881494Y672829D01*
X1883023Y674579D01*
G01X-25590Y9843D02*
G03X-15748Y0I9842J-1D01*
G01X-25590Y89370D02*
Y9843D01*
G01X-23622Y91339D02*
G03X-25590Y89370I1J-1969D01*
G01X-7874Y91339D02*
X-23622D01*
G01X-25590Y109055D02*
G03X-21653Y105118I3937J0D01*
G01X-25590Y357874D02*
Y109055D01*
G01X-21653Y105118D02*
X261811D01*
G01X-25590Y371654D02*
G03X-23622Y369685I1968J-1D01*
G01X-21653Y361811D02*
G03X-25590Y357874I0J-3937D01*
G01X1969Y361811D02*
X-21653D01*
G01X-7874Y369685D02*
X-23622D01*
G01X-25590Y459055D02*
Y371654D01*
G01X-23622Y461024D02*
G03X-25590Y459055I1J-1969D01*
G01X-7874Y461024D02*
X-23622D01*
G01X-25590Y478740D02*
G03X-21653Y474803I3937J0D01*
G01X-25590Y727559D02*
Y478740D01*
G01X-21653Y474803D02*
X261811D01*
G01X-21653Y731496D02*
G03X-25590Y727559I0J-3937D01*
G01X1969Y731496D02*
X-21653D01*
G01X-11811Y0D02*
G03X-7874Y3937I0J3937D01*
G01X-11811Y0D02*
X-15748D01*
G01X0Y3937D02*
G03X3937Y0I3937J0D01*
G01X-7874Y33071D02*
Y3937D01*
G01X0Y87402D02*
Y3937D01*
G01Y33071D02*
G03X-7874I-3937J0D01*
G01Y58268D02*
G03X0I3937J0D01*
G01X-7874Y91339D02*
Y58268D01*
G01X3937Y91339D02*
G03X0Y87402I0J-3937D01*
G01X5906Y357874D02*
G03X1969Y361811I-3937J0D01*
G01X0Y373622D02*
G03X3937Y369685I3937J0D01*
G01X-7874Y402756D02*
Y369685D01*
G01X0Y457087D02*
Y373622D01*
G01Y402756D02*
G03X-7874I-3937J0D01*
G01Y427953D02*
G03X0I3937J0D01*
G01X-7874Y461024D02*
Y427953D01*
G01X3937Y461024D02*
G03X0Y457087I0J-3937D01*
G01X5906Y727559D02*
G03X1969Y731496I-3937J0D01*
G01X3937Y0D02*
X372048D01*
G01X192914Y91339D02*
X3937D01*
G01X5906Y290748D02*
G03X9843Y286811I3937J0D01*
G01X5906Y357874D02*
Y290748D01*
G01X69488Y286811D02*
X9843D01*
G01X13780Y315650D02*
Y294685D01*
G01X69488D02*
X13780D01*
G01Y315650D02*
G03X5906I-3937J0D01*
G01Y340847D02*
G03X13780I3937J0D01*
G01Y361811D02*
Y340847D01*
G01X3937Y369685D02*
X372048D01*
G01X43307Y361811D02*
X13780D01*
G01X192914Y461024D02*
X3937D01*
G01X5906Y660433D02*
G03X9843Y656496I3937J0D01*
G01X5906Y727559D02*
Y660433D01*
G01X69488Y656496D02*
X9843D01*
G01X13780Y685335D02*
Y664370D01*
G01X69488D02*
X13780D01*
G01Y685335D02*
G03X5906I-3937J0D01*
G01Y710532D02*
G03X13780I3937J0D01*
G01Y729528D02*
Y710532D01*
G01X15748Y731496D02*
G03X13780Y729528I0J-1968D01*
G01X44819Y731496D02*
X15748D01*
G01X43307Y361811D02*
G03Y369685I0J3937D01*
G01X46675Y730184D02*
G03X44819Y731496I-1856J-657D01*
G01X46675Y730184D02*
G03X54098I3712J1313D01*
G01X53150Y181697D02*
G03X55118Y179729I1968J0D01*
G01X53150Y195477D02*
Y181697D01*
G01X55118Y179729D02*
X161418D01*
G01X55118Y197445D02*
G03X53150Y195477I0J-1968D01*
G01X161418Y197445D02*
X55118D01*
G01X73426Y282874D02*
G03X69488Y286811I-3937J0D01*
G01X81300Y282874D02*
G03X69488Y294685I-11811J0D01*
G01X74016Y369685D02*
G03Y361811I0J-3937D01*
G01X53150Y551382D02*
G03X55118Y549414I1968J0D01*
G01X53150Y565162D02*
Y551382D01*
G01X55118Y549414D02*
X161418D01*
G01X55118Y567130D02*
G03X53150Y565162I0J-1968D01*
G01X161418Y567130D02*
X55118D01*
G01X73426Y652559D02*
G03X69488Y656496I-3937J0D01*
G01X81300Y652559D02*
G03X69488Y664370I-11811J0D01*
G01X55954Y731496D02*
G03X54098Y730184I0J-1969D01*
G01X153544Y731496D02*
X55954D01*
G01X80709Y43307D02*
G03X82677Y41339I1968J0D01*
G01Y47244D02*
G03X80709Y45276I0J-1968D01*
G01X188977Y47244D02*
X82677D01*
G01Y41339D02*
X188977D01*
G01X80709Y45276D02*
Y43307D01*
G01X86614Y101181D02*
G03X82677Y105118I-3937J0D01*
G01X86614Y95276D02*
Y101181D01*
G01X82677Y91339D02*
G03X86614Y95276I0J3937D01*
G01X73426Y267323D02*
G03X77363Y263386I3937J0D01*
G01X73426Y267323D02*
Y282874D01*
G01X77363Y263386D02*
X159449D01*
G01X81300Y271260D02*
Y282874D01*
G01Y271260D02*
X155512D01*
G01Y361811D02*
X74016D01*
G01X80709Y412992D02*
G03X82677Y411024I1968J0D01*
G01Y416929D02*
G03X80709Y414961I0J-1968D01*
G01X188977Y416929D02*
X82677D01*
G01Y411024D02*
X188977D01*
G01X80709Y414961D02*
Y412992D01*
G01X86614Y464961D02*
Y470866D01*
G01X82677Y461024D02*
G03X86614Y464961I0J3937D01*
G01Y470866D02*
G03X82677Y474803I-3937J0D01*
G01X73426Y637008D02*
G03X77363Y633071I3937J0D01*
G01X73426Y637008D02*
Y652559D01*
G01X77363Y633071D02*
X159449D01*
G01X81300Y640945D02*
Y652559D01*
G01Y640945D02*
X155512D01*
G01X109449Y95276D02*
Y101181D01*
G01X113386Y105118D02*
G03X109449Y101181I0J-3937D01*
G01Y95276D02*
G03X113386Y91339I3937J0D01*
G01X109449Y464961D02*
Y470866D01*
G01Y464961D02*
G03X113386Y461024I3937J0D01*
G01Y474803D02*
G03X109449Y470866I0J-3937D01*
G01X161418Y179729D02*
G03X163386Y181697I0J1968D01*
G01Y195477D02*
G03X161418Y197445I-1968J0D01*
G01X159449Y263386D02*
G03X163386Y267323I0J3937D01*
G01X155512Y303937D02*
Y271260D01*
G01X163386Y303937D02*
G03X155512I-3937J0D01*
G01Y329134D02*
G03X163386I3937J0D01*
G01X155512Y361811D02*
Y329134D01*
G01X161418Y549414D02*
G03X163386Y551382I0J1968D01*
G01Y565162D02*
G03X161418Y567130I-1968J0D01*
G01X159449Y633071D02*
G03X163386Y637008I0J3937D01*
G01X155512Y673622D02*
Y640945D01*
G01X163386Y673622D02*
G03X155512I-3937J0D01*
G01Y698819D02*
G03X163386I3937J0D01*
G01X155512Y729528D02*
Y698819D01*
G01Y729528D02*
G03X153544Y731496I-1968J0D01*
G01X163386Y181697D02*
Y195477D01*
G01Y357874D02*
Y267323D01*
G01X167323Y361811D02*
G03X163386Y357874I0J-3937D01*
G01X535433Y361811D02*
X167323D01*
G01X163386Y551382D02*
Y565162D01*
G01Y727559D02*
Y637008D01*
G01X167323Y731496D02*
G03X163386Y727559I0J-3937D01*
G01X535433Y731496D02*
X167323D01*
G01X188977Y41339D02*
G03X190945Y43307I0J1968D01*
G01Y45276D02*
G03X188977Y47244I-1968J0D01*
G01X190945Y43307D02*
Y45276D01*
G01X196851Y97244D02*
G03X194882Y95276I0J-1969D01*
G01X192914Y91339D02*
G03X194882Y93307I0J1968D01*
G01X196851Y97244D02*
X269685D01*
G01X194882Y93307D02*
Y95276D01*
G01X188977Y411024D02*
G03X190945Y412992I0J1968D01*
G01Y414961D02*
G03X188977Y416929I-1968J0D01*
G01X190945Y412992D02*
Y414961D01*
G01X196851Y466929D02*
G03X194882Y464961I-1J-1968D01*
G01X192914Y461024D02*
G03X194882Y462992I0J1968D01*
G01D02*
Y464961D01*
G01X196851Y466929D02*
X269685D01*
G01Y97244D02*
G03X273622Y101181I0J3937D01*
G01Y252756D02*
Y101181D01*
G01X261811Y105118D02*
G03X265748Y109055I0J3937D01*
G01D02*
Y260630D01*
G01X273622Y165551D02*
G03X265748I-3937J0D01*
G01Y196260D02*
G03X273622I3937J0D01*
G01X269685Y264567D02*
G03X265748Y260630I0J-3937D01*
G01X277559Y256693D02*
G03X273622Y252756I0J-3937D01*
G01X342520Y264567D02*
X269685D01*
G01X254331Y361811D02*
G03Y369685I0J3937D01*
G01X261811Y474803D02*
G03X265748Y478740I0J3937D01*
G01D02*
Y630315D01*
G01X269685Y466929D02*
G03X273622Y470866I0J3937D01*
G01Y622441D02*
Y470866D01*
G01Y535236D02*
G03X265748I-3937J0D01*
G01Y565945D02*
G03X273622I3937J0D01*
G01X277559Y626378D02*
G03X273622Y622441I0J-3937D01*
G01X269685Y634252D02*
G03X265748Y630315I0J-3937D01*
G01X342520Y634252D02*
X269685D01*
G01X561024Y256693D02*
X277559D01*
G01X285040Y369685D02*
G03Y361811I0J-3937D01*
G01X561024Y626378D02*
X277559D01*
G01X342520Y264567D02*
G03X344488Y266536I0J1968D01*
G01X342520Y634252D02*
G03X344488Y636221I0J1968D01*
G01X346457Y270473D02*
G03X344488Y268504I0J-1969D01*
G01X346457Y270473D02*
X535433D01*
G01X344488Y268504D02*
Y266536D01*
G01X350394Y320473D02*
G03X348426Y318504I0J-1968D01*
G01Y316536D02*
G03X350394Y314567I1968J-1D01*
G01D02*
X456693D01*
G01Y320473D02*
X350394D01*
G01X348426Y318504D02*
Y316536D01*
G01X346457Y640158D02*
G03X344488Y638189I0J-1969D01*
G01X346457Y640158D02*
X535433D01*
G01X344488Y638189D02*
Y636221D01*
G01X350394Y690158D02*
G03X348426Y688189I0J-1968D01*
G01Y686221D02*
G03X350394Y684252I1968J-1D01*
G01D02*
X456693D01*
G01Y690158D02*
X350394D01*
G01X348426Y688189D02*
Y686221D01*
G01X383859Y1969D02*
G03X385827Y0I1968J-1D01*
G01D02*
X523622D01*
G01X372048D02*
G03X375985Y3937I0J3937D01*
G01X383859Y1969D02*
Y32677D01*
G01X375985Y3937D02*
Y94488D01*
G01X383859Y32677D02*
G03X375985I-3937J0D01*
G01Y57874D02*
G03X383859I3937J0D01*
G01D02*
Y90551D01*
G01X379922Y98425D02*
G03X375985Y94488I0J-3937D01*
G01X458071Y90551D02*
X383859D01*
G01X462008Y98425D02*
X379922D01*
G01X375985Y166334D02*
G03X377953Y164365I1969J0D01*
G01X375985Y180113D02*
Y166334D01*
G01X377953Y164365D02*
X484252D01*
G01X377953Y182082D02*
G03X375985Y180113I0J-1968D01*
G01X484252Y182082D02*
X377953D01*
G01X383859Y369685D02*
X465355D01*
G01X372048D02*
G03X375985Y373622I0J3937D01*
G01X383859Y369685D02*
Y402362D01*
G01X375985Y373622D02*
Y464173D01*
G01X383859Y402362D02*
G03X375985I-3937J0D01*
G01Y427559D02*
G03X383859I3937J0D01*
G01D02*
Y460236D01*
G01X379922Y468110D02*
G03X375985Y464173I0J-3937D01*
G01X458071Y460236D02*
X383859D01*
G01X462008Y468110D02*
X379922D01*
G01X375985Y536019D02*
G03X377953Y534050I1969J0D01*
G01D02*
X484252D01*
G01X377953Y551767D02*
G03X375985Y549799I0J-1968D01*
G01D02*
Y536019D01*
G01X484252Y551767D02*
X377953D01*
G01X429922Y260630D02*
Y266536D01*
G01X425985Y256693D02*
G03X429922Y260630I0J3937D01*
G01Y266536D02*
G03X425985Y270473I-3937J0D01*
G01X429922Y630315D02*
Y636221D01*
G01X425985Y626378D02*
G03X429922Y630315I0J3937D01*
G01Y636221D02*
G03X425985Y640158I-3937J0D01*
G01X452756Y260630D02*
G03X456693Y256693I3937J0D01*
G01X452756Y260630D02*
Y266536D01*
G01X456693Y270473D02*
G03X452756Y266536I0J-3937D01*
G01X458662Y318504D02*
G03X456693Y320473I-1969J0D01*
G01Y314567D02*
G03X458662Y316536I0J1969D01*
G01X452756Y630315D02*
G03X456693Y626378I3937J0D01*
G01X452756Y630315D02*
Y636221D01*
G01X456693Y640158D02*
G03X452756Y636221I0J-3937D01*
G01X458662Y688189D02*
G03X456693Y690158I-1969J0D01*
G01Y684252D02*
G03X458662Y686221I0J1969D01*
G01X458071Y78937D02*
G03X469882Y67126I11811J0D01*
G01X465945Y78937D02*
G03X469882Y75000I3937J0D01*
G01X458071Y90551D02*
Y78937D01*
G01X465945Y94488D02*
Y78937D01*
G01X469882Y67126D02*
X525591D01*
G01X469882Y75000D02*
X529528D01*
G01X465945Y94488D02*
G03X462008Y98425I-3937J0D01*
G01X458662Y316536D02*
Y318504D01*
G01X465355Y361811D02*
G03Y369685I0J3937D01*
G01X458071Y448622D02*
G03X469882Y436811I11811J0D01*
G01D02*
X525591D01*
G01X465945Y448622D02*
G03X469882Y444685I3937J0D01*
G01X465945Y464173D02*
G03X462008Y468110I-3937J0D01*
G01X458071Y460236D02*
Y448622D01*
G01X465945Y464173D02*
Y448622D01*
G01X469882Y444685D02*
X529528D01*
G01X458662Y686221D02*
Y688189D01*
G01X484252Y164365D02*
G03X486221Y166334I0J1969D01*
G01D02*
Y180113D01*
G01D02*
G03X484252Y182082I-1969J0D01*
G01X496063Y369685D02*
G03Y361811I0J-3937D01*
G01Y369685D02*
X525591D01*
G01X484252Y534050D02*
G03X486221Y536019I0J1969D01*
G01Y549799D02*
G03X484252Y551767I-1969J-1D01*
G01X486221Y536019D02*
Y549799D01*
G01X523622Y0D02*
G03X525591Y1969I0J1969D01*
G01X533465Y3937D02*
G03X537402Y0I3937J0D01*
G01X525591Y1969D02*
Y20965D01*
G01X533465Y3937D02*
Y71063D01*
G01X537402Y0D02*
X561024D01*
G01X533465Y20965D02*
G03X525591I-3937J0D01*
G01Y46162D02*
G03X533465I3937J0D01*
G01X525591D02*
Y67126D01*
G01X533465Y71063D02*
G03X529528Y75000I-3937J0D01*
G01X535433Y270473D02*
G03X539370Y274410I0J3937D01*
G01D02*
Y357874D01*
G01X547244Y270473D02*
X562992D01*
G01X547244D02*
Y303543D01*
G01D02*
G03X539370I-3937J0D01*
G01Y328740D02*
G03X547244I3937J0D01*
G01D02*
Y361811D01*
G01X539370Y357874D02*
G03X535433Y361811I-3937J0D01*
G01X547244D02*
X562992D01*
G01X533465Y373622D02*
G03X537402Y369685I3937J0D01*
G01X525591D02*
Y390650D01*
G01X533465Y373622D02*
Y440748D01*
G01X537402Y369685D02*
X561024D01*
G01X533465Y390650D02*
G03X525591I-3937J0D01*
G01Y415847D02*
G03X533465I3937J0D01*
G01X525591D02*
Y436811D01*
G01X533465Y440748D02*
G03X529528Y444685I-3937J0D01*
G01X535433Y640158D02*
G03X539370Y644095I0J3937D01*
G01D02*
Y727559D01*
G01X547244Y640158D02*
X562992D01*
G01X547244D02*
Y673228D01*
G01D02*
G03X539370I-3937J0D01*
G01Y698425D02*
G03X547244I3937J0D01*
G01D02*
Y727559D01*
G01X551181Y731496D02*
G03X547244Y727559I0J-3937D01*
G01X539370D02*
G03X535433Y731496I-3937J0D01*
G01X561024Y0D02*
G03X564961Y3937I0J3937D01*
G01D02*
Y252756D01*
G01D02*
G03X561024Y256693I-3937J0D01*
G01X562992Y270473D02*
G03X564961Y272441I1J1968D01*
G01D02*
Y359843D01*
G01D02*
G03X562992Y361811I-1968J0D01*
G01X561024Y369685D02*
G03X564961Y373622I0J3937D01*
G01D02*
Y622441D01*
G01D02*
G03X561024Y626378I-3937J0D01*
G01X562992Y640158D02*
G03X564961Y642126I1J1968D01*
G01D02*
Y721654D01*
G01D02*
G03X555118Y731496I-9842J0D01*
G01X551181D02*
X555118D01*
G54D12*
G01X303900Y28900D02*
X306460Y31460D01*
G01D02*
Y32950D01*
G01X313900Y27200D02*
X313840Y27260D01*
G01D02*
Y33000D01*
G01X321380D02*
X318960D01*
G01X322100Y32280D02*
X321380Y33000D01*
G01X322100Y26600D02*
Y32280D01*
M02*
